# T6G (Grand Teton) — schematic netlist excerpt (pin names and nets, part order shuffled) for the footprints in the layout excerpt that follows; sources: Cadence DE-HDL packaged netlist, KiCad conversion of 04192023_DAF0TMB3IC0_F0TG_MB_C_brd_V02_OCP.brd

R538  Q_RES  2.2K 5% CHIP  pkg 0402LF  page 54 : A = CPU1_XTRIG_L5 ; B = PVDD18_S5_P1
C2400  Q_CAP  22UF 4V 20% X6S  pkg C0402  page 73 : A = PVDDCR_CPU1_P1 ; B = GND

(kicad_pcb
	(version 20260206)
	(generator "pcbnew")
	(generator_version "10.0")
	(general
		(thickness 1.6)
		(legacy_teardrops no)
	)
	(paper "A4")
	(title_block
		(title "04192023_DAF0TMB3IC0_F0TG_MB_C_brd_V02_OCP.brd")
		(comment 1 "Grand Teton / footprints 6685-6686 of 8354")
	)
	(layers
		(0 "F.Cu" signal "TOP")
		(4 "In1.Cu" signal "GND")
		(6 "In2.Cu" signal "IN1")
		(8 "In3.Cu" signal "GND1")
		(10 "In4.Cu" signal "IN2")
		(12 "In5.Cu" signal "GND2")
		(14 "In6.Cu" signal "IN3")
		(16 "In7.Cu" signal "GND3")
		(18 "In8.Cu" signal "VCC")
		(20 "In9.Cu" signal "VCC1")
		(22 "In10.Cu" signal "GND4")
		(24 "In11.Cu" signal "IN4")
		(26 "In12.Cu" signal "GND5")
		(28 "In13.Cu" signal "IN5")
		(30 "In14.Cu" signal "GND6")
		(32 "In15.Cu" signal "IN6")
		(34 "In16.Cu" signal "GND7")
		(2 "B.Cu" signal "BOTTOM")
		(9 "F.Adhes" user "F.Adhesive")
		(11 "B.Adhes" user "B.Adhesive")
		(13 "F.Paste" user "Package Geometry/Pastemask Top")
		(15 "B.Paste" user "Package Geometry/Pastemask Bottom")
		(5 "F.SilkS" user "Ref Des/Silkscreen Top")
		(7 "B.SilkS" user "Ref Des/Silkscreen Bottom")
		(1 "F.Mask" user "Board Geometry/Soldermask Top")
		(3 "B.Mask" user "Board Geometry/Soldermask Bottom")
		(17 "Dwgs.User" user "User.Drawings")
		(19 "Cmts.User" user "User.Comments")
		(21 "Eco1.User" user "User.Eco1")
		(23 "Eco2.User" user "User.Eco2")
		(25 "Edge.Cuts" user "Board Geometry/Outline")
		(27 "Margin" user)
		(31 "F.CrtYd" user "Package Geometry/Place Bound Top")
		(29 "B.CrtYd" user "Package Geometry/Place Bound Bottom")
		(35 "F.Fab" user "Ref Des/Assembly Top")
		(33 "B.Fab" user "Ref Des/Assembly Bottom")
	)
	(footprint ""
		(layer "B.Cu")
		(at 116.372386 -268.418564)
		(property "Reference" "C2400"
			(at 0 0 0)
			(layer "B.SilkS")
			(hide yes)
			(effects
				(font
					(size 1.27 1.27)
				)
				(justify mirror)
			)
		)
		(property "Value" ""
			(at 0 0 0)
			(layer "B.Fab")
			(effects
				(font
					(size 1.27 1.27)
				)
				(justify mirror)
			)
		)
		(duplicate_pad_numbers_are_jumpers no)
		(fp_line
			(start -0.7874 -0.4064)
			(end -0.7874 0.4064)
			(stroke
				(width 0.1524)
				(type default)
			)
			(layer "B.SilkS")
		)
		(fp_line
			(start -0.7874 0.4064)
			(end 0.7874 0.4064)
			(stroke
				(width 0.1524)
				(type default)
			)
			(layer "B.SilkS")
		)
		(fp_line
			(start 0.7874 -0.4064)
			(end -0.7874 -0.4064)
			(stroke
				(width 0.1524)
				(type default)
			)
			(layer "B.SilkS")
		)
		(fp_line
			(start 0.7874 0.4064)
			(end 0.7874 -0.4064)
			(stroke
				(width 0.1524)
				(type default)
			)
			(layer "B.SilkS")
		)
		(fp_line
			(start -0.67945 -0.3048)
			(end -0.67945 0.3048)
			(stroke
				(width 0.1)
				(type default)
			)
			(layer "B.Fab")
		)
		(fp_line
			(start -0.67945 0.3048)
			(end -0.120396 0.3048)
			(stroke
				(width 0.1)
				(type default)
			)
			(layer "B.Fab")
		)
		(fp_line
			(start -0.12065 -0.3048)
			(end -0.67945 -0.3048)
			(stroke
				(width 0.1)
				(type default)
			)
			(layer "B.Fab")
		)
		(fp_line
			(start -0.12065 -0.2794)
			(end -0.12065 -0.3048)
			(stroke
				(width 0.1)
				(type default)
			)
			(layer "B.Fab")
		)
		(fp_line
			(start -0.120396 0.2794)
			(end 0.12065 0.2794)
			(stroke
				(width 0.1)
				(type default)
			)
			(layer "B.Fab")
		)
		(fp_line
			(start -0.120396 0.3048)
			(end -0.120396 0.2794)
			(stroke
				(width 0.1)
				(type default)
			)
			(layer "B.Fab")
		)
		(fp_line
			(start 0.12065 -0.305054)
			(end 0.12065 -0.2794)
			(stroke
				(width 0.1)
				(type default)
			)
			(layer "B.Fab")
		)
		(fp_line
			(start 0.12065 -0.2794)
			(end -0.12065 -0.2794)
			(stroke
				(width 0.1)
				(type default)
			)
			(layer "B.Fab")
		)
		(fp_line
			(start 0.12065 0.2794)
			(end 0.12065 0.3048)
			(stroke
				(width 0.1)
				(type default)
			)
			(layer "B.Fab")
		)
		(fp_line
			(start 0.12065 0.3048)
			(end 0.67945 0.3048)
			(stroke
				(width 0.1)
				(type default)
			)
			(layer "B.Fab")
		)
		(fp_line
			(start 0.67945 -0.305054)
			(end 0.12065 -0.305054)
			(stroke
				(width 0.1)
				(type default)
			)
			(layer "B.Fab")
		)
		(fp_line
			(start 0.67945 0.3048)
			(end 0.67945 -0.305054)
			(stroke
				(width 0.1)
				(type default)
			)
			(layer "B.Fab")
		)
		(pad "1" smd circle
			(at 0.40005 0 180)
			(size 0 0)
			(layers "B.Cu" "B.Mask" "B.Paste")
			(net "PVDDCR_CPU1_P1")
		)
		(pad "2" smd circle
			(at -0.40005 0 180)
			(size 0 0)
			(layers "B.Cu" "B.Mask" "B.Paste")
			(net "GND")
		)
	)
	(footprint ""
		(layer "B.Cu")
		(at 91.392502 -205.14945 90)
		(property "Reference" "R538"
			(at 0 0 90)
			(layer "B.SilkS")
			(hide yes)
			(effects
				(font
					(size 1.27 1.27)
				)
				(justify mirror)
			)
		)
		(property "Value" ""
			(at 0 0 90)
			(layer "B.Fab")
			(effects
				(font
					(size 1.27 1.27)
				)
				(justify mirror)
			)
		)
		(duplicate_pad_numbers_are_jumpers no)
		(fp_line
			(start 0.7874 -0.4064)
			(end -0.7874 -0.4064)
			(stroke
				(width 0.1524)
				(type default)
			)
			(layer "B.SilkS")
		)
		(fp_line
			(start -0.7874 -0.4064)
			(end -0.7874 0.4064)
			(stroke
				(width 0.1524)
				(type default)
			)
			(layer "B.SilkS")
		)
		(fp_line
			(start 0.7874 0.4064)
			(end 0.7874 -0.4064)
			(stroke
				(width 0.1524)
				(type default)
			)
			(layer "B.SilkS")
		)
		(fp_line
			(start -0.7874 0.4064)
			(end 0.7874 0.4064)
			(stroke
				(width 0.1524)
				(type default)
			)
			(layer "B.SilkS")
		)
		(fp_line
			(start 0.67945 -0.305054)
			(end 0.12065 -0.305054)
			(stroke
				(width 0.1)
				(type default)
			)
			(layer "B.Fab")
		)
		(fp_line
			(start 0.12065 -0.305054)
			(end 0.12065 -0.2794)
			(stroke
				(width 0.1)
				(type default)
			)
			(layer "B.Fab")
		)
		(fp_line
			(start -0.12065 -0.3048)
			(end -0.67945 -0.3048)
			(stroke
				(width 0.1)
				(type default)
			)
			(layer "B.Fab")
		)
		(fp_line
			(start -0.67945 -0.3048)
			(end -0.67945 0.3048)
			(stroke
				(width 0.1)
				(type default)
			)
			(layer "B.Fab")
		)
		(fp_line
			(start 0.12065 -0.2794)
			(end -0.12065 -0.2794)
			(stroke
				(width 0.1)
				(type default)
			)
			(layer "B.Fab")
		)
		(fp_line
			(start -0.12065 -0.2794)
			(end -0.12065 -0.3048)
			(stroke
				(width 0.1)
				(type default)
			)
			(layer "B.Fab")
		)
		(fp_line
			(start 0.12065 0.2794)
			(end 0.12065 0.3048)
			(stroke
				(width 0.1)
				(type default)
			)
			(layer "B.Fab")
		)
		(fp_line
			(start -0.120396 0.2794)
			(end 0.12065 0.2794)
			(stroke
				(width 0.1)
				(type default)
			)
			(layer "B.Fab")
		)
		(fp_line
			(start 0.67945 0.3048)
			(end 0.67945 -0.305054)
			(stroke
				(width 0.1)
				(type default)
			)
			(layer "B.Fab")
		)
		(fp_line
			(start 0.12065 0.3048)
			(end 0.67945 0.3048)
			(stroke
				(width 0.1)
				(type default)
			)
			(layer "B.Fab")
		)
		(fp_line
			(start -0.120396 0.3048)
			(end -0.120396 0.2794)
			(stroke
				(width 0.1)
				(type default)
			)
			(layer "B.Fab")
		)
		(fp_line
			(start -0.67945 0.3048)
			(end -0.120396 0.3048)
			(stroke
				(width 0.1)
				(type default)
			)
			(layer "B.Fab")
		)
		(pad "1" smd circle
			(at 0.40005 0 270)
			(size 0 0)
			(layers "B.Cu" "B.Mask" "B.Paste")
			(net "CPU1_XTRIG_L5")
		)
		(pad "2" smd circle
			(at -0.40005 0 270)
			(size 0 0)
			(layers "B.Cu" "B.Mask" "B.Paste")
			(net "PVDD18_S5_P1")
		)
	)
)
